# BASEBOARD_FAB2 (Tioga Pass) — schematic netlist excerpt (pin names and nets, part order shuffled) for the footprints in the layout excerpt that follows; sources: Cadence DE-HDL packaged netlist, KiCad conversion of Wiwynn_Tioga_Pass_MB.brd

R1U17  RES  1.00K 1% CHIP  pkg 0402  page 164 : A = FM_BOARD_SKU_ID2 ; B = GND
C2R2  CAP_A  0.1UF 16V 10% X7R  pkg 0402V  page 192 : A = P3V3_STBY ; B = GND
R3L11  RES  100.0 1% EMPTY  pkg 0402  page 218 : A = PVCCIO_CPU0 ; B = SVID_DIO1_CPU0_R

(kicad_pcb
	(version 20260206)
	(generator "pcbnew")
	(generator_version "10.0")
	(general
		(thickness 1.6)
		(legacy_teardrops no)
	)
	(paper "A4")
	(title_block
		(title "Wiwynn_Tioga_Pass_MB.brd")
		(comment 1 "Tioga Pass / footprints 4327-4329 of 4770")
	)
	(layers
		(0 "F.Cu" signal "TOP")
		(4 "In1.Cu" signal "L2GND")
		(6 "In2.Cu" signal "L3")
		(8 "In3.Cu" signal "L4GND")
		(10 "In4.Cu" signal "L5")
		(12 "In5.Cu" signal "L6GND")
		(14 "In6.Cu" signal "L7VCC")
		(16 "In7.Cu" signal "L8VCC")
		(18 "In8.Cu" signal "L9GND")
		(20 "In9.Cu" signal "L10")
		(22 "In10.Cu" signal "L11GND")
		(24 "In11.Cu" signal "L12")
		(26 "In12.Cu" signal "L13GND")
		(2 "B.Cu" signal "BOTTOM")
		(9 "F.Adhes" user "F.Adhesive")
		(11 "B.Adhes" user "B.Adhesive")
		(13 "F.Paste" user "Package Geometry/Pastemask Top")
		(15 "B.Paste" user "Package Geometry/Pastemask Bottom")
		(5 "F.SilkS" user "Ref Des/Silkscreen Top")
		(7 "B.SilkS" user "Ref Des/Silkscreen Bottom")
		(1 "F.Mask" user "Board Geometry/Soldermask Top")
		(3 "B.Mask" user "Board Geometry/Soldermask Bottom")
		(17 "Dwgs.User" user "User.Drawings")
		(19 "Cmts.User" user "User.Comments")
		(21 "Eco1.User" user "User.Eco1")
		(23 "Eco2.User" user "User.Eco2")
		(25 "Edge.Cuts" user "Board Geometry/Outline")
		(27 "Margin" user)
		(31 "F.CrtYd" user "Package Geometry/Place Bound Top")
		(29 "B.CrtYd" user "Package Geometry/Place Bound Bottom")
		(35 "F.Fab" user "Ref Des/Assembly Top")
		(33 "B.Fab" user "Ref Des/Assembly Bottom")
	)
	(footprint ""
		(layer "B.Cu")
		(at 370.745512 -72.294242)
		(property "Reference" "C2R2"
			(at 0 0 0)
			(layer "B.SilkS")
			(hide yes)
			(effects
				(font
					(size 1.27 1.27)
				)
				(justify mirror)
			)
		)
		(property "Value" ""
			(at 0 0 0)
			(layer "B.Fab")
			(effects
				(font
					(size 1.27 1.27)
				)
				(justify mirror)
			)
		)
		(duplicate_pad_numbers_are_jumpers no)
		(fp_rect
			(start 0.2794 0.9144)
			(end -0.2794 -0.1143)
			(stroke
				(width 0)
				(type default)
			)
			(fill no)
			(layer "B.CrtYd")
		)
		(fp_line
			(start -0.2794 -0.1143)
			(end -0.2794 0.9144)
			(stroke
				(width 0.1)
				(type default)
			)
			(layer "B.Fab")
		)
		(fp_line
			(start -0.2794 0.9144)
			(end 0.2794 0.9144)
			(stroke
				(width 0.1)
				(type default)
			)
			(layer "B.Fab")
		)
		(fp_line
			(start 0.2794 -0.1143)
			(end -0.2794 -0.1143)
			(stroke
				(width 0.1)
				(type default)
			)
			(layer "B.Fab")
		)
		(fp_line
			(start 0.2794 0.9144)
			(end 0.2794 -0.1143)
			(stroke
				(width 0.1)
				(type default)
			)
			(layer "B.Fab")
		)
		(pad "1" smd custom
			(at 0 0 270)
			(size 0.10414 0.10414)
			(layers "B.Cu" "B.Mask" "B.Paste")
			(net "P3V3_STBY")
			(options
				(clearance outline)
				(anchor circle)
			)
			(primitives
				(gr_poly
					(pts
						(xy -0.20828 -0.08636) (xy -0.20828 0.08636) (xy -0.08636 0.20828) (xy 0.086614 0.20828) (xy 0.20828 0.086614)
						(xy 0.20828 -0.08636) (xy 0.08636 -0.20828) (xy -0.08636 -0.20828)
					)
					(width 0)
					(fill yes)
				)
			)
		)
		(pad "2" smd custom
			(at 0 0.8001 270)
			(size 0.10414 0.10414)
			(layers "B.Cu" "B.Mask" "B.Paste")
			(net "GND")
			(options
				(clearance outline)
				(anchor circle)
			)
			(primitives
				(gr_poly
					(pts
						(xy -0.20828 -0.08636) (xy -0.20828 0.08636) (xy -0.08636 0.20828) (xy 0.086614 0.20828) (xy 0.20828 0.086614)
						(xy 0.20828 -0.08636) (xy 0.08636 -0.20828) (xy -0.08636 -0.20828)
					)
					(width 0)
					(fill yes)
				)
			)
		)
		(zone
			(layer "B.Cu")
			(hatch none 0.5)
			(connect_pads
				(clearance 0)
			)
			(min_thickness 0.25)
			(keepout
				(tracks not_allowed)
				(vias allowed)
				(pads allowed)
				(copperpour not_allowed)
				(footprints allowed)
			)
			(placement
				(enabled no)
				(sheetname "")
			)
			(fill
				(thermal_gap 0.5)
				(thermal_bridge_width 0.5)
				(island_removal_mode 0)
			)
			(polygon
				(pts
					(xy 370.833142 -72.084692) (xy 370.833142 -71.703692) (xy 370.657882 -71.703692) (xy 370.657628 -72.084692)
				)
			)
		)
		(zone
			(layer "B.Cu")
			(hatch none 0.5)
			(connect_pads
				(clearance 0)
			)
			(min_thickness 0.25)
			(keepout
				(tracks allowed)
				(vias not_allowed)
				(pads allowed)
				(copperpour not_allowed)
				(footprints allowed)
			)
			(placement
				(enabled no)
				(sheetname "")
			)
			(fill
				(thermal_gap 0.5)
				(thermal_bridge_width 0.5)
				(island_removal_mode 0)
			)
			(polygon
				(pts
					(xy 370.833142 -72.084692) (xy 370.833142 -71.703692) (xy 370.657882 -71.703692) (xy 370.657628 -72.084692)
				)
			)
		)
	)
	(footprint ""
		(layer "B.Cu")
		(at 432.0032 -23.4188)
		(property "Reference" "R1U17"
			(at 0 0 0)
			(layer "B.SilkS")
			(hide yes)
			(effects
				(font
					(size 1.27 1.27)
				)
				(justify mirror)
			)
		)
		(property "Value" ""
			(at 0 0 0)
			(layer "B.Fab")
			(effects
				(font
					(size 1.27 1.27)
				)
				(justify mirror)
			)
		)
		(duplicate_pad_numbers_are_jumpers no)
		(fp_poly
			(pts
				(xy 0.2794 -0.1016) (xy -0.2794 -0.1016) (xy -0.2794 0.9906) (xy 0.2794 0.9906)
			)
			(stroke
				(width 0)
				(type default)
			)
			(fill no)
			(layer "B.CrtYd")
		)
		(fp_line
			(start -0.2794 -0.1016)
			(end 0.2794 -0.1016)
			(stroke
				(width 0.1)
				(type default)
			)
			(layer "B.Fab")
		)
		(fp_line
			(start -0.2794 0.9906)
			(end -0.2794 -0.1016)
			(stroke
				(width 0.1)
				(type default)
			)
			(layer "B.Fab")
		)
		(fp_line
			(start 0.2794 -0.1016)
			(end 0.2794 0.9906)
			(stroke
				(width 0.1)
				(type default)
			)
			(layer "B.Fab")
		)
		(fp_line
			(start 0.2794 0.9906)
			(end -0.2794 0.9906)
			(stroke
				(width 0.1)
				(type default)
			)
			(layer "B.Fab")
		)
		(pad "1" smd rect
			(at 0 0 180)
			(size 0.508 0.508)
			(layers "B.Cu" "B.Mask" "B.Paste")
			(net "FM_BOARD_SKU_ID2")
		)
		(pad "2" smd rect
			(at 0 0.889 180)
			(size 0.508 0.508)
			(layers "B.Cu" "B.Mask" "B.Paste")
			(net "GND")
		)
		(zone
			(layer "B.Cu")
			(hatch none 0.5)
			(connect_pads
				(clearance 0)
			)
			(min_thickness 0.25)
			(keepout
				(tracks allowed)
				(vias not_allowed)
				(pads allowed)
				(copperpour not_allowed)
				(footprints allowed)
			)
			(placement
				(enabled no)
				(sheetname "")
			)
			(fill
				(thermal_gap 0.5)
				(thermal_bridge_width 0.5)
				(island_removal_mode 0)
			)
			(polygon
				(pts
					(xy 432.2572 -23.1648) (xy 431.7492 -23.1648) (xy 431.7492 -22.7838) (xy 432.2572 -22.7838)
				)
			)
		)
		(zone
			(layer "B.Cu")
			(hatch none 0.5)
			(connect_pads
				(clearance 0)
			)
			(min_thickness 0.25)
			(keepout
				(tracks not_allowed)
				(vias allowed)
				(pads allowed)
				(copperpour not_allowed)
				(footprints allowed)
			)
			(placement
				(enabled no)
				(sheetname "")
			)
			(fill
				(thermal_gap 0.5)
				(thermal_bridge_width 0.5)
				(island_removal_mode 0)
			)
			(polygon
				(pts
					(xy 432.2572 -22.7838) (xy 431.7492 -22.7838) (xy 431.7492 -23.1648) (xy 432.2572 -23.1648)
				)
			)
		)
	)
	(footprint ""
		(layer "B.Cu")
		(at 363.87024 -138.41857 90)
		(property "Reference" "R3L11"
			(at 0 0 90)
			(layer "B.SilkS")
			(hide yes)
			(effects
				(font
					(size 1.27 1.27)
				)
				(justify mirror)
			)
		)
		(property "Value" ""
			(at 0 0 90)
			(layer "B.Fab")
			(effects
				(font
					(size 1.27 1.27)
				)
				(justify mirror)
			)
		)
		(duplicate_pad_numbers_are_jumpers no)
		(fp_rect
			(start -0.2794 -0.1016)
			(end 0.2794 0.9906)
			(stroke
				(width 0)
				(type default)
			)
			(fill no)
			(layer "B.CrtYd")
		)
		(fp_line
			(start 0.2794 -0.1016)
			(end 0.2794 0.9906)
			(stroke
				(width 0.1)
				(type default)
			)
			(layer "B.Fab")
		)
		(fp_line
			(start -0.2794 -0.1016)
			(end 0.2794 -0.1016)
			(stroke
				(width 0.1)
				(type default)
			)
			(layer "B.Fab")
		)
		(fp_line
			(start 0.2794 0.9906)
			(end -0.2794 0.9906)
			(stroke
				(width 0.1)
				(type default)
			)
			(layer "B.Fab")
		)
		(fp_line
			(start -0.2794 0.9906)
			(end -0.2794 -0.1016)
			(stroke
				(width 0.1)
				(type default)
			)
			(layer "B.Fab")
		)
		(pad "1" smd rect
			(at 0 0 270)
			(size 0.508 0.508)
			(layers "B.Cu" "B.Mask" "B.Paste")
			(net "PVCCIO_CPU0")
		)
		(pad "2" smd rect
			(at 0 0.889 270)
			(size 0.508 0.508)
			(layers "B.Cu" "B.Mask" "B.Paste")
			(net "SVID_DIO1_CPU0_R")
		)
		(zone
			(layer "B.Cu")
			(hatch none 0.5)
			(connect_pads
				(clearance 0)
			)
			(min_thickness 0.25)
			(keepout
				(tracks not_allowed)
				(vias allowed)
				(pads allowed)
				(copperpour not_allowed)
				(footprints allowed)
			)
			(placement
				(enabled no)
				(sheetname "")
			)
			(fill
				(thermal_gap 0.5)
				(thermal_bridge_width 0.5)
				(island_removal_mode 0)
			)
			(polygon
				(pts
					(xy 364.12424 -138.16457) (xy 364.50524 -138.16457) (xy 364.50524 -138.67257) (xy 364.12424 -138.67257)
				)
			)
		)
		(zone
			(layer "B.Cu")
			(hatch none 0.5)
			(connect_pads
				(clearance 0)
			)
			(min_thickness 0.25)
			(keepout
				(tracks allowed)
				(vias not_allowed)
				(pads allowed)
				(copperpour not_allowed)
				(footprints allowed)
			)
			(placement
				(enabled no)
				(sheetname "")
			)
			(fill
				(thermal_gap 0.5)
				(thermal_bridge_width 0.5)
				(island_removal_mode 0)
			)
			(polygon
				(pts
					(xy 364.12424 -138.16457) (xy 364.50524 -138.16457) (xy 364.50524 -138.67257) (xy 364.12424 -138.67257)
				)
			)
		)
	)
)
